# BASEBOARD_FAB2 (Tioga Pass) — schematic parts with pin connectivity, parts 973–1156 of 4751; source: Cadence DE-HDL packaged netlist (pstxprt.dat, pstxnet.dat, pstchip.dat)

C5A8  CAP_A  47UF 4V 20% X5R  pkg 0603V  page 220 : 1 = PVDDQ_DEF ; 2 = GND
C5A9  CAP_A  47UF 4V 20% X5R  pkg 0603V  page 220 : 1 = PVDDQ_DEF ; 2 = GND
C5A10  CAP  100UF 4V 20% X5R  pkg 0805  page 220 : 1 = PVDDQ_DEF ; 2 = GND
C5A11  CAP_A  47UF 4V 20% X5R  pkg 0603V  page 220 : 1 = PVDDQ_DEF ; 2 = GND
C5A12  CAP_A  47UF 4V 20% X5R  pkg 0603V  page 220 : 1 = PVDDQ_DEF ; 2 = GND
C5A13  CAP_A  47UF 4V 20% X5R  pkg 0603V  page 220 : 1 = PVDDQ_DEF ; 2 = GND
C5A14  CAP_A  47UF 4V 20% X5R  pkg 0603V  page 220 : 1 = PVDDQ_DEF ; 2 = GND
C5A15  CAP_A  47UF 4V 20% X5R  pkg 0603V  page 220 : 1 = PVDDQ_DEF ; 2 = GND
C5A16  CAP_A  47UF 4V 20% X5R  pkg 0603V  page 220 : 1 = PVDDQ_DEF ; 2 = GND
C5A17  CAP_A  47UF 4V 20% X5R  pkg 0603V  page 220 : 1 = PVDDQ_DEF ; 2 = GND
C5A18  CAP_A  47UF 4V 20% X5R  pkg 0603V  page 220 : 1 = PVDDQ_DEF ; 2 = GND
C5A19  CAP_A  47UF 4V 20% X5R  pkg 0603V  page 220 : 1 = PVDDQ_DEF ; 2 = GND
C5A20  CAP  100UF 4V 20% X5R  pkg 0805  page 220 : 1 = PVDDQ_DEF ; 2 = GND
C5B1  CAP_A  47UF 4V 20% X5R  pkg 0603V  page 220 : 1 = PVDDQ_DEF ; 2 = GND
C5B2  CAP_A  47UF 4V 20% X5R  pkg 0603V  page 220 : 1 = PVDDQ_DEF ; 2 = GND
C5D1  CAP_A  22.0UF 4V 20% X6S  pkg 0603V  page 220 : 1 = PVDDQ_DEF ; 2 = GND
C5D2  CAP_A  22.0UF 4V 20% X6S  pkg 0603V  page 220 : 1 = PVDDQ_DEF ; 2 = GND
C5D3  CAP_A  22.0UF 4V 20% X6S  pkg 0603V  page 220 : 1 = PVDDQ_DEF ; 2 = GND
C5D4  CAP_A  22.0UF 4V 20% X6S  pkg 0603V  page 220 : 1 = PVDDQ_DEF ; 2 = GND
C5D5  CAP_A  22.0UF 4V 20% X6S  pkg 0603V  page 42 : 1 = PVCCIN_CPU0 ; 2 = GND
C5D6  CAP_A  22.0UF 4V 20% X6S  pkg 0603V  page 220 : 1 = PVDDQ_DEF ; 2 = GND
C5D7  CAP_A  22.0UF 4V 20% X6S  pkg 0603V  page 220 : 1 = PVDDQ_DEF ; 2 = GND
C5D8  CAP_A  22.0UF 4V 20% X6S  pkg 0603V  page 220 : 1 = PVDDQ_DEF ; 2 = GND
C5D9  CAP_A  22.0UF 4V 20% X6S  pkg 0603V  page 220 : 1 = PVDDQ_DEF ; 2 = GND
C5D10  CAP  10UF 4V 20% X6S  pkg 0603LF  page 42 : 1 = PVSA_CPU0 ; 2 = GND
C5D11  CAP  10UF 4V 20% X6S  pkg 0603LF  page 42 : 1 = PVSA_CPU0 ; 2 = GND
C5D12  CAP  10UF 4V 20% X6S  pkg 0603LF  page 42 : 1 = PVSA_CPU0 ; 2 = GND
C5D13  CAP  10UF 4V 20% X6S  pkg 0603LF  page 42 : 1 = PVSA_CPU0 ; 2 = GND
C5D14  CAP_A  22.0UF 4V 20% X6S  pkg 0603V  page 42 : 1 = PVCCIN_CPU0 ; 2 = GND
C5D15  CAP_A  22.0UF 4V 20% X6S  pkg 0603V  page 42 : 1 = PVCCIN_CPU0 ; 2 = GND
C5D16  CAP_A  22.0UF 4V 20% X6S  pkg 0603V  page 42 : 1 = PVCCIN_CPU0 ; 2 = GND
C5D17  CAP_A  22.0UF 4V 20% X6S  pkg 0603V  page 42 : 1 = PVCCIN_CPU0 ; 2 = GND
C5D18  CAP_A  22.0UF 4V 20% X6S  pkg 0603V  page 42 : 1 = PVCCIN_CPU0 ; 2 = GND
C5D19  CAP_A  22.0UF 4V 20% X6S  pkg 0603V  page 42 : 1 = PVCCIN_CPU0 ; 2 = GND
C5D20  CAP_A  22.0UF 4V 20% X6S  pkg 0603V  page 42 : 1 = PVCCMCP_CPU0 ; 2 = GND
C5D21  CAP_A  22.0UF 4V 20% X6S  pkg 0603V  page 42 : 1 = PVCCMCP_CPU0 ; 2 = GND
C5D22  CAP_A  22.0UF 4V 20% X6S  pkg 0603V  page 42 : 1 = PVCCMCP_CPU0 ; 2 = GND
C5D23  CAP_A  22.0UF 4V 20% X6S  pkg 0603V  page 42 : 1 = PVCCMCP_CPU0 ; 2 = GND
C5D24  CAP_A  22.0UF 4V 20% X6S  pkg 0603V  page 42 : 1 = PVCCIN_CPU0 ; 2 = GND
C5D25  CAP_A  22.0UF 4V 20% X6S  pkg 0603V  page 42 : 1 = PVCCIN_CPU0 ; 2 = GND
C5D26  CAP_A  22.0UF 4V 20% X6S  pkg 0603V  page 42 : 1 = PVCCIN_CPU0 ; 2 = GND
C5D27  CAP_A  22.0UF 4V 20% X6S  pkg 0603V  page 42 : 1 = PVCCIN_CPU0 ; 2 = GND
C5D28  CAP_A  22.0UF 4V 20% X6S  pkg 0603V  page 42 : 1 = PVCCIN_CPU0 ; 2 = GND
C5D29  CAP_A  22.0UF 4V 20% X6S  pkg 0603V  page 42 : 1 = PVCCIN_CPU0 ; 2 = GND
C5D30  CAP_A  22.0UF 4V 20% X6S  pkg 0603V  page 42 : 1 = PVCCIN_CPU0 ; 2 = GND
C5D31  CAP_A  22.0UF 4V 20% X6S  pkg 0603V  page 42 : 1 = PVCCIN_CPU0 ; 2 = GND
C5D32  CAP_A  22.0UF 4V 20% X6S  pkg 0603V  page 42 : 1 = PVCCIN_CPU0 ; 2 = GND
C5D33  CAP_A  22.0UF 4V 20% X6S  pkg 0603V  page 42 : 1 = PVCCMCP_CPU0 ; 2 = GND
C5D34  CAP_A  22.0UF 4V 20% X6S  pkg 0603V  page 42 : 1 = PVCCMCP_CPU0 ; 2 = GND
C5D35  CAP_A  22.0UF 4V 20% X6S  pkg 0603V  page 42 : 1 = PVCCMCP_CPU0 ; 2 = GND
C5D36  CAP_A  22.0UF 4V 20% X6S  pkg 0603V  page 42 : 1 = PVCCMCP_CPU0 ; 2 = GND
C5D37  CAP_A  22.0UF 4V 20% X6S  pkg 0603V  page 42 : 1 = PVCCMCP_CPU0 ; 2 = GND
C5D38  CAP_A  22.0UF 4V 20% X6S  pkg 0603V  page 42 : 1 = PVCCMCP_CPU0 ; 2 = GND
C5D39  CAP_A  22.0UF 4V 20% X6S  pkg 0603V  page 42 : 1 = PVCCIN_CPU0 ; 2 = GND
C5D40  CAP_A  22.0UF 4V 20% X6S  pkg 0603V  page 42 : 1 = PVCCIN_CPU0 ; 2 = GND
C5D41  CAP_A  22.0UF 4V 20% X6S  pkg 0603V  page 42 : 1 = PVCCIN_CPU0 ; 2 = GND
C5D42  CAP_A  22.0UF 4V 20% X6S  pkg 0603V  page 42 : 1 = PVCCIN_CPU0 ; 2 = GND
C5D43  CAP_A  22.0UF 4V 20% X6S  pkg 0603V  page 42 : 1 = PVCCIN_CPU0 ; 2 = GND
C5D44  CAP_A  22.0UF 4V 20% X6S  pkg 0603V  page 42 : 1 = PVCCIN_CPU0 ; 2 = GND
C5D45  CAP_A  22.0UF 4V 20% X6S  pkg 0603V  page 42 : 1 = PVCCIN_CPU0 ; 2 = GND
C5D46  CAP_A  22.0UF 4V 20% X6S  pkg 0603V  page 42 : 1 = PVCCIN_CPU0 ; 2 = GND
C5D47  CAP_A  22.0UF 4V 20% X6S  pkg 0603V  page 42 : 1 = PVCCIN_CPU0 ; 2 = GND
C5D48  CAP_A  22.0UF 4V 20% X6S  pkg 0603V  page 42 : 1 = PVCCMCP_CPU0 ; 2 = GND
C5D49  CAP_A  22.0UF 4V 20% X6S  pkg 0603V  page 42 : 1 = PVCCMCP_CPU0 ; 2 = GND
C5D50  CAP_A  22.0UF 4V 20% X6S  pkg 0603V  page 42 : 1 = PVCCMCP_CPU0 ; 2 = GND
C5D51  CAP_A  22.0UF 4V 20% X6S  pkg 0603V  page 42 : 1 = PVCCMCP_CPU0 ; 2 = GND
C5D52  CAP_A  22.0UF 4V 20% X6S  pkg 0603V  page 42 : 1 = PVCCMCP_CPU0 ; 2 = GND
C5D53  CAP_A  22.0UF 4V 20% X6S  pkg 0603V  page 42 : 1 = PVCCMCP_CPU0 ; 2 = GND
C5D54  CAP_A  22.0UF 4V 20% X6S  pkg 0603V  page 217 : 1 = PVDDQ_ABC ; 2 = GND
C5D55  CAP_A  22.0UF 4V 20% X6S  pkg 0603V  page 217 : 1 = PVDDQ_ABC ; 2 = GND
C5D56  CAP_A  22.0UF 4V 20% X6S  pkg 0603V  page 217 : 1 = PVDDQ_ABC ; 2 = GND
C5D57  CAP_A  22.0UF 4V 20% X6S  pkg 0603V  page 217 : 1 = PVDDQ_ABC ; 2 = GND
C5D58  CAP_A  22.0UF 4V 20% X6S  pkg 0603V  page 217 : 1 = PVDDQ_ABC ; 2 = GND
C5D59  CAP_A  22.0UF 4V 20% X6S  pkg 0603V  page 217 : 1 = PVDDQ_ABC ; 2 = GND
C5D60  CAP_A  22.0UF 4V 20% X6S  pkg 0603V  page 217 : 1 = PVDDQ_ABC ; 2 = GND
C5D61  CAP_A  22.0UF 4V 20% X6S  pkg 0603V  page 217 : 1 = PVDDQ_ABC ; 2 = GND
C5F1  CAP_A  47UF 4V 20% X5R  pkg 0603V  page 217 : 1 = PVDDQ_ABC ; 2 = GND
C5F2  CAP_A  47UF 4V 20% X5R  pkg 0603V  page 217 : 1 = PVDDQ_ABC ; 2 = GND
C5G1  CAP_A  47UF 4V 20% X5R  pkg 0603V  page 217 : 1 = PVDDQ_ABC ; 2 = GND
C5G2  CAP_A  47UF 4V 20% X5R  pkg 0603V  page 217 : 1 = PVDDQ_ABC ; 2 = GND
C5G3  CAP_A  47UF 4V 20% X5R  pkg 0603V  page 217 : 1 = PVDDQ_ABC ; 2 = GND
C5G4  CAP_A  47UF 4V 20% X5R  pkg 0603V  page 217 : 1 = PVDDQ_ABC ; 2 = GND
C5G5  CAP_A  47UF 4V 20% X5R  pkg 0603V  page 217 : 1 = PVDDQ_ABC ; 2 = GND
C5G6  CAP_A  47UF 4V 20% X5R  pkg 0603V  page 217 : 1 = PVDDQ_ABC ; 2 = GND
C5G7  CAP_A  47UF 4V 20% X5R  pkg 0603V  page 217 : 1 = PVDDQ_ABC ; 2 = GND
C5G8  CAP_A  47UF 4V 20% X5R  pkg 0603V  page 217 : 1 = PVDDQ_ABC ; 2 = GND
C5G9  CAP  100UF 4V 20% X5R  pkg 0805  page 217 : 1 = PVDDQ_ABC ; 2 = GND
C5G10  CAP_A  47UF 4V 20% X5R  pkg 0603V  page 217 : 1 = PVDDQ_ABC ; 2 = GND
C5G11  CAP_A  47UF 4V 20% X5R  pkg 0603V  page 217 : 1 = PVDDQ_ABC ; 2 = GND
C5G12  CAP_A  47UF 4V 20% X5R  pkg 0603V  page 217 : 1 = PVDDQ_ABC ; 2 = GND
C5G13  CAP_A  47UF 4V 20% X5R  pkg 0603V  page 217 : 1 = PVDDQ_ABC ; 2 = GND
C5G14  CAP_A  47UF 4V 20% X5R  pkg 0603V  page 217 : 1 = PVDDQ_ABC ; 2 = GND
C5G15  CAP_A  47UF 4V 20% X5R  pkg 0603V  page 217 : 1 = PVDDQ_ABC ; 2 = GND
C5G16  CAP_A  47UF 4V 20% X5R  pkg 0603V  page 217 : 1 = PVDDQ_ABC ; 2 = GND
C5G17  CAP_A  47UF 4V 20% X5R  pkg 0603V  page 217 : 1 = PVDDQ_ABC ; 2 = GND
C5G18  CAP_A  47UF 4V 20% X5R  pkg 0603V  page 217 : 1 = PVDDQ_ABC ; 2 = GND
C5G19  CAP_A  47UF 4V 20% X5R  pkg 0603V  page 217 : 1 = PVDDQ_ABC ; 2 = GND
C5G20  CAP  100UF 4V 20% X5R  pkg 0805  page 217 : 1 = PVDDQ_ABC ; 2 = GND
C5G21  CAP  47UF 4V 20% X6S  pkg 0805  page 242 : 1 = PVDDQ_ABC ; 2 = GND
C5G22  CAP  47UF 4V 20% X6S  pkg 0805  page 242 : 1 = PVDDQ_ABC ; 2 = GND
C5G41  CAP_A  22.0UF 4V 20% X6S  pkg 0603V  page 242 : 1 = PVDDQ_ABC ; 2 = GND
C5G42  CAP_A  22.0UF 4V 20% X6S  pkg 0603V  page 242 : 1 = PVDDQ_ABC ; 2 = GND
C5G43  CAP_A  22.0UF 4V 20% X6S  pkg 0603V  page 242 : 1 = PVDDQ_ABC ; 2 = GND
C5G44  CAP_A  22.0UF 4V 20% X6S  pkg 0603V  page 242 : 1 = PVDDQ_ABC ; 2 = GND
C5G45  CAP_A  22.0UF 4V 20% X6S  pkg 0603V  page 242 : 1 = PVDDQ_ABC ; 2 = GND
C5G46  CAP_A  22.0UF 4V 20% X6S  pkg 0603V  page 242 : 1 = PVDDQ_ABC ; 2 = GND
C5G47  CAP_A  22.0UF 4V 20% X6S  pkg 0603V  page 242 : 1 = PVDDQ_ABC ; 2 = GND
C5G48  CAP_A  22.0UF 4V 20% X6S  pkg 0603V  page 242 : 1 = PVDDQ_ABC ; 2 = GND
C5G49  CAP_A  22.0UF 4V 20% X6S  pkg 0603V  page 242 : 1 = PVDDQ_ABC ; 2 = GND
C5G50  CAP_A  22.0UF 4V 20% X6S  pkg 0603V  page 242 : 1 = PVDDQ_ABC ; 2 = GND
C5G51  CAP_A  22.0UF 4V 20% X6S  pkg 0603V  page 242 : 1 = PVDDQ_ABC ; 2 = GND
C5G52  CAP_A  22.0UF 4V 20% X6S  pkg 0603V  page 242 : 1 = PVDDQ_ABC ; 2 = GND
C5G53  CAP_A  22.0UF 4V 20% X6S  pkg 0603V  page 242 : 1 = PVDDQ_ABC ; 2 = GND
C5G54  CAP_A  22.0UF 4V 20% X6S  pkg 0603V  page 242 : 1 = PVDDQ_ABC ; 2 = GND
C5G55  CAP_A  22.0UF 4V 20% X6S  pkg 0603V  page 242 : 1 = PVDDQ_ABC ; 2 = GND
C5G56  CAP_A  22.0UF 4V 20% X6S  pkg 0603V  page 242 : 1 = PVDDQ_ABC ; 2 = GND
C5G57  CAP_A  22.0UF 4V 20% X6S  pkg 0603V  page 242 : 1 = PVDDQ_ABC ; 2 = GND
C5G58  CAP_A  22.0UF 4V 20% X6S  pkg 0603V  page 242 : 1 = PVDDQ_ABC ; 2 = GND
C5G59  CAP_A  22.0UF 4V 20% X6S  pkg 0603V  page 242 : 1 = PVDDQ_DEF ; 2 = GND
C5G60  CAP_A  22.0UF 4V 20% X6S  pkg 0603V  page 242 : 1 = PVDDQ_DEF ; 2 = GND
C5G61  CAP_A  22.0UF 4V 20% X6S  pkg 0603V  page 242 : 1 = PVDDQ_DEF ; 2 = GND
C5G62  CAP_A  22.0UF 4V 20% X6S  pkg 0603V  page 242 : 1 = PVDDQ_DEF ; 2 = GND
C5G63  CAP_A  22.0UF 4V 20% X6S  pkg 0603V  page 242 : 1 = PVDDQ_DEF ; 2 = GND
C5G64  CAP_A  22.0UF 4V 20% X6S  pkg 0603V  page 242 : 1 = PVDDQ_DEF ; 2 = GND
C5G65  CAP_A  22.0UF 4V 20% X6S  pkg 0603V  page 242 : 1 = PVDDQ_DEF ; 2 = GND
C5G66  CAP_A  22.0UF 4V 20% X6S  pkg 0603V  page 242 : 1 = PVDDQ_DEF ; 2 = GND
C5G67  CAP_A  22.0UF 4V 20% X6S  pkg 0603V  page 242 : 1 = PVDDQ_DEF ; 2 = GND
C5G68  CAP_A  22.0UF 4V 20% X6S  pkg 0603V  page 242 : 1 = PVDDQ_DEF ; 2 = GND
C5G69  CAP_A  22.0UF 4V 20% X6S  pkg 0603V  page 242 : 1 = PVDDQ_DEF ; 2 = GND
C5G70  CAP_A  22.0UF 4V 20% X6S  pkg 0603V  page 242 : 1 = PVDDQ_DEF ; 2 = GND
C5G71  CAP_A  22.0UF 4V 20% X6S  pkg 0603V  page 242 : 1 = PVDDQ_DEF ; 2 = GND
C5G72  CAP_A  22.0UF 4V 20% X6S  pkg 0603V  page 242 : 1 = PVDDQ_DEF ; 2 = GND
C5G73  CAP_A  22.0UF 4V 20% X6S  pkg 0603V  page 242 : 1 = PVDDQ_DEF ; 2 = GND
C5G74  CAP_A  22.0UF 4V 20% X6S  pkg 0603V  page 242 : 1 = PVDDQ_DEF ; 2 = GND
C5G75  CAP_A  22.0UF 4V 20% X6S  pkg 0603V  page 242 : 1 = PVDDQ_DEF ; 2 = GND
C5G76  CAP_A  22.0UF 4V 20% X6S  pkg 0603V  page 242 : 1 = PVDDQ_DEF ; 2 = GND
C5G77  CAP  47UF 4V 20% X6S  pkg 0805  page 242 : 1 = PVDDQ_DEF ; 2 = GND
C5G78  CAP  47UF 4V 20% X6S  pkg 0805  page 242 : 1 = PVDDQ_DEF ; 2 = GND
C5G79  CAP_A  22.0UF 4V 20% X6S  pkg 0603V  page 243 : 1 = PVDDQ_GHJ ; 2 = GND
C5G80  CAP_A  22.0UF 4V 20% X6S  pkg 0603V  page 243 : 1 = PVDDQ_GHJ ; 2 = GND
C5G81  CAP_A  22.0UF 4V 20% X6S  pkg 0603V  page 243 : 1 = PVDDQ_GHJ ; 2 = GND
C5G82  CAP_A  22.0UF 4V 20% X6S  pkg 0603V  page 243 : 1 = PVDDQ_GHJ ; 2 = GND
C5G83  CAP_A  22.0UF 4V 20% X6S  pkg 0603V  page 243 : 1 = PVDDQ_GHJ ; 2 = GND
C5G84  CAP_A  22.0UF 4V 20% X6S  pkg 0603V  page 243 : 1 = PVDDQ_GHJ ; 2 = GND
C5G85  CAP_A  22.0UF 4V 20% X6S  pkg 0603V  page 243 : 1 = PVDDQ_GHJ ; 2 = GND
C5G86  CAP_A  22.0UF 4V 20% X6S  pkg 0603V  page 243 : 1 = PVDDQ_GHJ ; 2 = GND
C5G87  CAP_A  22.0UF 4V 20% X6S  pkg 0603V  page 243 : 1 = PVDDQ_GHJ ; 2 = GND
C5G88  CAP_A  22.0UF 4V 20% X6S  pkg 0603V  page 243 : 1 = PVDDQ_GHJ ; 2 = GND
C5G89  CAP_A  22.0UF 4V 20% X6S  pkg 0603V  page 243 : 1 = PVDDQ_GHJ ; 2 = GND
C5G90  CAP_A  22.0UF 4V 20% X6S  pkg 0603V  page 243 : 1 = PVDDQ_GHJ ; 2 = GND
C5G91  CAP_A  22.0UF 4V 20% X6S  pkg 0603V  page 243 : 1 = PVDDQ_GHJ ; 2 = GND
C5G92  CAP_A  22.0UF 4V 20% X6S  pkg 0603V  page 243 : 1 = PVDDQ_GHJ ; 2 = GND
C5G93  CAP_A  22.0UF 4V 20% X6S  pkg 0603V  page 243 : 1 = PVDDQ_GHJ ; 2 = GND
C5G94  CAP_A  22.0UF 4V 20% X6S  pkg 0603V  page 243 : 1 = PVDDQ_GHJ ; 2 = GND
C5G95  CAP_A  22.0UF 4V 20% X6S  pkg 0603V  page 243 : 1 = PVDDQ_GHJ ; 2 = GND
C5G96  CAP_A  22.0UF 4V 20% X6S  pkg 0603V  page 243 : 1 = PVDDQ_GHJ ; 2 = GND
C5G97  CAP_A  22.0UF 4V 20% X6S  pkg 0603V  page 243 : 1 = PVDDQ_KLM ; 2 = GND
C5G98  CAP_A  22.0UF 4V 20% X6S  pkg 0603V  page 243 : 1 = PVDDQ_KLM ; 2 = GND
C5G99  CAP_A  22.0UF 4V 20% X6S  pkg 0603V  page 243 : 1 = PVDDQ_KLM ; 2 = GND
C5G100  CAP_A  22.0UF 4V 20% X6S  pkg 0603V  page 243 : 1 = PVDDQ_KLM ; 2 = GND
C5G101  CAP_A  22.0UF 4V 20% X6S  pkg 0603V  page 243 : 1 = PVDDQ_KLM ; 2 = GND
C5G102  CAP_A  22.0UF 4V 20% X6S  pkg 0603V  page 243 : 1 = PVDDQ_KLM ; 2 = GND
C5G103  CAP_A  22.0UF 4V 20% X6S  pkg 0603V  page 243 : 1 = PVDDQ_KLM ; 2 = GND
C5G104  CAP_A  22.0UF 4V 20% X6S  pkg 0603V  page 243 : 1 = PVDDQ_KLM ; 2 = GND
C5G105  CAP_A  22.0UF 4V 20% X6S  pkg 0603V  page 243 : 1 = PVDDQ_KLM ; 2 = GND
C5G106  CAP_A  22.0UF 4V 20% X6S  pkg 0603V  page 243 : 1 = PVDDQ_KLM ; 2 = GND
C5G107  CAP_A  22.0UF 4V 20% X6S  pkg 0603V  page 243 : 1 = PVDDQ_KLM ; 2 = GND
C5G108  CAP_A  22.0UF 4V 20% X6S  pkg 0603V  page 243 : 1 = PVDDQ_KLM ; 2 = GND
C5G109  CAP_A  22.0UF 4V 20% X6S  pkg 0603V  page 243 : 1 = PVDDQ_KLM ; 2 = GND
C5G110  CAP_A  22.0UF 4V 20% X6S  pkg 0603V  page 243 : 1 = PVDDQ_KLM ; 2 = GND
C5G111  CAP_A  22.0UF 4V 20% X6S  pkg 0603V  page 243 : 1 = PVDDQ_KLM ; 2 = GND
C5G112  CAP_A  22.0UF 4V 20% X6S  pkg 0603V  page 243 : 1 = PVDDQ_KLM ; 2 = GND
C5G113  CAP_A  22.0UF 4V 20% X6S  pkg 0603V  page 243 : 1 = PVDDQ_KLM ; 2 = GND
C5G114  CAP_A  22.0UF 4V 20% X6S  pkg 0603V  page 243 : 1 = PVDDQ_KLM ; 2 = GND
C5G115  CAP  47UF 4V 20% X6S  pkg 0805  page 243 : 1 = PVDDQ_KLM ; 2 = GND
C5G116  CAP  47UF 4V 20% X6S  pkg 0805  page 243 : 1 = PVDDQ_KLM ; 2 = GND
C5G117  CAP  47UF 4V 20% X6S  pkg 0805  page 243 : 1 = PVDDQ_GHJ ; 2 = GND
C5G118  CAP  47UF 4V 20% X6S  pkg 0805  page 243 : 1 = PVDDQ_GHJ ; 2 = GND
C5L1  CAP  100UF 4V 20% X5R  pkg 0805  page 220 : 1 = PVDDQ_DEF ; 2 = GND
C5L2  CAP  100UF 4V 20% X5R  pkg 0805  page 220 : 1 = PVDDQ_DEF ; 2 = GND
C5L3  CAP  100UF 4V 20% X5R  pkg 0805  page 220 : 1 = PVDDQ_DEF ; 2 = GND
C5L4  CAP  100UF 4V 20% X5R  pkg 0805  page 222 : 1 = PVTT_DEF ; 2 = GND
C5L5  CAP  100UF 4V 20% X5R  pkg 0805  page 222 : 1 = PVTT_DEF ; 2 = GND
C5L6  CAP_A  47UF 4V 20% X5R  pkg 0603V  page 220 : 1 = PVDDQ_DEF ; 2 = GND
